# SCM (Grand Teton) — schematic netlist excerpt (pin names and nets, part order shuffled) for the footprints in the layout excerpt that follows; sources: Cadence DE-HDL packaged netlist, KiCad conversion of 12092022_DA0F0TMDCD0_F0T_Management_Board_D_brd_V3_OCP.brd

C134  Q_CAP  0.01UF 50V 10% X7R  pkg C0402  page 17 : A = GND ; B = A_BMC_ADCVREFN0
C163  Q_CAP  10UF 16V 20% X6S  pkg C0603  page 41 : A = PVCCA_AUX_PLD ; B = GND

(kicad_pcb
	(version 20260206)
	(generator "pcbnew")
	(generator_version "10.0")
	(general
		(thickness 1.6)
		(legacy_teardrops no)
	)
	(paper "A4")
	(title_block
		(title "12092022_DA0F0TMDCD0_F0T_Management_Board_D_brd_V3_OCP.brd")
		(comment 1 "Grand Teton / footprints 932-933 of 1440")
	)
	(layers
		(0 "F.Cu" signal "TOP")
		(4 "In1.Cu" signal "GND")
		(6 "In2.Cu" signal "IN1")
		(8 "In3.Cu" signal "GND1")
		(10 "In4.Cu" signal "IN2")
		(12 "In5.Cu" signal "VCC")
		(14 "In6.Cu" signal "VCC1")
		(16 "In7.Cu" signal "IN3")
		(18 "In8.Cu" signal "GND2")
		(20 "In9.Cu" signal "IN4")
		(22 "In10.Cu" signal "GND3")
		(2 "B.Cu" signal "BOTTOM")
		(9 "F.Adhes" user "F.Adhesive")
		(11 "B.Adhes" user "B.Adhesive")
		(13 "F.Paste" user "Package Geometry/Pastemask Top")
		(15 "B.Paste" user "Package Geometry/Pastemask Bottom")
		(5 "F.SilkS" user "Ref Des/Silkscreen Top")
		(7 "B.SilkS" user "Ref Des/Silkscreen Bottom")
		(1 "F.Mask" user "Board Geometry/Soldermask Top")
		(3 "B.Mask" user "Board Geometry/Soldermask Bottom")
		(17 "Dwgs.User" user "User.Drawings")
		(19 "Cmts.User" user "User.Comments")
		(21 "Eco1.User" user "User.Eco1")
		(23 "Eco2.User" user "User.Eco2")
		(25 "Edge.Cuts" user "Board Geometry/Outline")
		(27 "Margin" user)
		(31 "F.CrtYd" user "Package Geometry/Place Bound Top")
		(29 "B.CrtYd" user "Package Geometry/Place Bound Bottom")
		(35 "F.Fab" user "Ref Des/Assembly Top")
		(33 "B.Fab" user "Ref Des/Assembly Bottom")
	)
	(footprint ""
		(layer "B.Cu")
		(at 46.0502 -61.976 90)
		(property "Reference" "C134"
			(at 0 0 90)
			(layer "B.SilkS")
			(hide yes)
			(effects
				(font
					(size 1.27 1.27)
				)
				(justify mirror)
			)
		)
		(property "Value" ""
			(at 0 0 90)
			(layer "B.Fab")
			(effects
				(font
					(size 1.27 1.27)
				)
				(justify mirror)
			)
		)
		(duplicate_pad_numbers_are_jumpers no)
		(fp_line
			(start 0.7874 -0.4064)
			(end -0.7874 -0.4064)
			(stroke
				(width 0.1524)
				(type default)
			)
			(layer "B.SilkS")
		)
		(fp_line
			(start -0.7874 -0.4064)
			(end -0.7874 0.4064)
			(stroke
				(width 0.1524)
				(type default)
			)
			(layer "B.SilkS")
		)
		(fp_line
			(start 0.7874 0.4064)
			(end 0.7874 -0.4064)
			(stroke
				(width 0.1524)
				(type default)
			)
			(layer "B.SilkS")
		)
		(fp_line
			(start -0.7874 0.4064)
			(end 0.7874 0.4064)
			(stroke
				(width 0.1524)
				(type default)
			)
			(layer "B.SilkS")
		)
		(fp_line
			(start 0.67945 -0.305054)
			(end 0.12065 -0.305054)
			(stroke
				(width 0.1)
				(type default)
			)
			(layer "B.Fab")
		)
		(fp_line
			(start 0.12065 -0.305054)
			(end 0.12065 -0.2794)
			(stroke
				(width 0.1)
				(type default)
			)
			(layer "B.Fab")
		)
		(fp_line
			(start -0.12065 -0.3048)
			(end -0.67945 -0.3048)
			(stroke
				(width 0.1)
				(type default)
			)
			(layer "B.Fab")
		)
		(fp_line
			(start -0.67945 -0.3048)
			(end -0.67945 0.3048)
			(stroke
				(width 0.1)
				(type default)
			)
			(layer "B.Fab")
		)
		(fp_line
			(start 0.12065 -0.2794)
			(end -0.12065 -0.2794)
			(stroke
				(width 0.1)
				(type default)
			)
			(layer "B.Fab")
		)
		(fp_line
			(start -0.12065 -0.2794)
			(end -0.12065 -0.3048)
			(stroke
				(width 0.1)
				(type default)
			)
			(layer "B.Fab")
		)
		(fp_line
			(start 0.12065 0.2794)
			(end 0.12065 0.3048)
			(stroke
				(width 0.1)
				(type default)
			)
			(layer "B.Fab")
		)
		(fp_line
			(start -0.120396 0.2794)
			(end 0.12065 0.2794)
			(stroke
				(width 0.1)
				(type default)
			)
			(layer "B.Fab")
		)
		(fp_line
			(start 0.67945 0.3048)
			(end 0.67945 -0.305054)
			(stroke
				(width 0.1)
				(type default)
			)
			(layer "B.Fab")
		)
		(fp_line
			(start 0.12065 0.3048)
			(end 0.67945 0.3048)
			(stroke
				(width 0.1)
				(type default)
			)
			(layer "B.Fab")
		)
		(fp_line
			(start -0.120396 0.3048)
			(end -0.120396 0.2794)
			(stroke
				(width 0.1)
				(type default)
			)
			(layer "B.Fab")
		)
		(fp_line
			(start -0.67945 0.3048)
			(end -0.120396 0.3048)
			(stroke
				(width 0.1)
				(type default)
			)
			(layer "B.Fab")
		)
		(pad "1" smd circle
			(at 0.40005 0 270)
			(size 0 0)
			(layers "B.Cu" "B.Mask" "B.Paste")
			(net "GND")
		)
		(pad "2" smd circle
			(at -0.40005 0 270)
			(size 0 0)
			(layers "B.Cu" "B.Mask" "B.Paste")
			(net "A_BMC_ADCVREFN0")
		)
	)
	(footprint ""
		(layer "B.Cu")
		(at 15.748 -100.711 135)
		(property "Reference" "C163"
			(at 0 0 135)
			(layer "B.SilkS")
			(hide yes)
			(effects
				(font
					(size 1.27 1.27)
				)
				(justify mirror)
			)
		)
		(property "Value" ""
			(at 0 0 135)
			(layer "B.Fab")
			(effects
				(font
					(size 1.27 1.27)
				)
				(justify mirror)
			)
		)
		(duplicate_pad_numbers_are_jumpers no)
		(fp_line
			(start 1.295492 -0.584255)
			(end -1.295492 -0.584255)
			(stroke
				(width 0.1524)
				(type default)
			)
			(layer "B.SilkS")
		)
		(fp_line
			(start 1.295492 0.584255)
			(end 1.295492 -0.584255)
			(stroke
				(width 0.1524)
				(type default)
			)
			(layer "B.SilkS")
		)
		(fp_line
			(start 0 -0.584076)
			(end 0 0.584076)
			(stroke
				(width 0.1524)
				(type default)
			)
			(layer "B.SilkS")
		)
		(fp_line
			(start -1.295492 -0.584255)
			(end -1.295492 0.584255)
			(stroke
				(width 0.1524)
				(type default)
			)
			(layer "B.SilkS")
		)
		(fp_line
			(start -1.295492 0.584255)
			(end 1.295492 0.584255)
			(stroke
				(width 0.1524)
				(type default)
			)
			(layer "B.SilkS")
		)
		(fp_line
			(start 1.193835 -0.406446)
			(end 0.863721 -0.406446)
			(stroke
				(width 0.1)
				(type default)
			)
			(layer "B.Fab")
		)
		(fp_line
			(start 0.863541 -0.457275)
			(end -0.863541 -0.457275)
			(stroke
				(width 0.1)
				(type default)
			)
			(layer "B.Fab")
		)
		(fp_line
			(start 0.863721 -0.406446)
			(end 0.863541 -0.457275)
			(stroke
				(width 0.1)
				(type default)
			)
			(layer "B.Fab")
		)
		(fp_line
			(start 1.193835 0.406446)
			(end 1.193835 -0.406446)
			(stroke
				(width 0.1)
				(type default)
			)
			(layer "B.Fab")
		)
		(fp_line
			(start 0.863721 0.406446)
			(end 1.193835 0.406446)
			(stroke
				(width 0.1)
				(type default)
			)
			(layer "B.Fab")
		)
		(fp_line
			(start 0.863541 0.457275)
			(end 0.863721 0.406446)
			(stroke
				(width 0.1)
				(type default)
			)
			(layer "B.Fab")
		)
		(fp_line
			(start -0.863541 -0.457275)
			(end -0.863721 -0.406446)
			(stroke
				(width 0.1)
				(type default)
			)
			(layer "B.Fab")
		)
		(fp_line
			(start -0.863721 -0.406446)
			(end -1.193835 -0.406446)
			(stroke
				(width 0.1)
				(type default)
			)
			(layer "B.Fab")
		)
		(fp_line
			(start -1.193835 -0.406446)
			(end -1.193835 0.406446)
			(stroke
				(width 0.1)
				(type default)
			)
			(layer "B.Fab")
		)
		(fp_line
			(start -0.863721 0.406446)
			(end -0.863541 0.457275)
			(stroke
				(width 0.1)
				(type default)
			)
			(layer "B.Fab")
		)
		(fp_line
			(start -0.863541 0.457275)
			(end 0.863541 0.457275)
			(stroke
				(width 0.1)
				(type default)
			)
			(layer "B.Fab")
		)
		(fp_line
			(start -1.193835 0.406446)
			(end -0.863721 0.406446)
			(stroke
				(width 0.1)
				(type default)
			)
			(layer "B.Fab")
		)
		(pad "1" smd rect
			(at 0.7366 0 45)
			(size 0.7112 0.8128)
			(layers "B.Cu" "B.Mask" "B.Paste")
			(net "PVCCA_AUX_PLD")
		)
		(pad "2" smd rect
			(at -0.7366 0 45)
			(size 0.7112 0.8128)
			(layers "B.Cu" "B.Mask" "B.Paste")
			(net "GND")
		)
	)
)
